(kicad_pcb
	(version 20260206)
	(generator "pcbnew")
	(generator_version "10.0")
	(general
		(thickness 1.6)
		(legacy_teardrops no)
	)
	(paper "A4")
	(title_block
		(title "12092022_DA0F0TMDCD0_F0T_Management_Board_D_brd_V3_OCP.brd")
		(comment 1 "Grand Teton / footprint 162 of 1440 (U25), pads 229-256 of 256")
	)
	(layers
		(0 "F.Cu" signal "TOP")
		(4 "In1.Cu" signal "GND")
		(6 "In2.Cu" signal "IN1")
		(8 "In3.Cu" signal "GND1")
		(10 "In4.Cu" signal "IN2")
		(12 "In5.Cu" signal "VCC")
		(14 "In6.Cu" signal "VCC1")
		(16 "In7.Cu" signal "IN3")
		(18 "In8.Cu" signal "GND2")
		(20 "In9.Cu" signal "IN4")
		(22 "In10.Cu" signal "GND3")
		(2 "B.Cu" signal "BOTTOM")
		(9 "F.Adhes" user "F.Adhesive")
		(11 "B.Adhes" user "B.Adhesive")
		(13 "F.Paste" user "Package Geometry/Pastemask Top")
		(15 "B.Paste" user "Package Geometry/Pastemask Bottom")
		(5 "F.SilkS" user "Ref Des/Silkscreen Top")
		(7 "B.SilkS" user "Ref Des/Silkscreen Bottom")
		(1 "F.Mask" user "Board Geometry/Soldermask Top")
		(3 "B.Mask" user "Board Geometry/Soldermask Bottom")
		(17 "Dwgs.User" user "User.Drawings")
		(19 "Cmts.User" user "User.Comments")
		(21 "Eco1.User" user "User.Eco1")
		(23 "Eco2.User" user "User.Eco2")
		(25 "Edge.Cuts" user "Board Geometry/Outline")
		(27 "Margin" user)
		(31 "F.CrtYd" user "Package Geometry/Place Bound Top")
		(29 "B.CrtYd" user "Package Geometry/Place Bound Bottom")
		(35 "F.Fab" user "Ref Des/Assembly Top")
		(33 "B.Fab" user "Ref Des/Assembly Bottom")
	)
	(footprint ""
		(layer "F.Cu")
		(at 21.459444 -93.587062 180)
		(property "Reference" "U25"
			(at -10.595356 -8.218932 0)
			(unlocked yes)
			(layer "F.SilkS")
			(effects
				(font
					(size 0.7874 0.5842)
					(thickness 0.1524)
				)
				(justify left)
			)
		)
		(property "Value" ""
			(at 0 0 180)
			(layer "F.Fab")
			(effects
				(font
					(size 1.27 1.27)
				)
			)
		)
		(duplicate_pad_numbers_are_jumpers no)
		(pad "R5" smd circle
			(at -2.800096 5.199888 180)
			(size 0.4064 0.4064)
			(layers "F.Cu" "F.Mask" "F.Paste")
			(net "FM_DEBUG_PORT_R2_PRSNT_N")
		)
		(pad "R6" smd circle
			(at -1.999996 5.199888 180)
			(size 0.4064 0.4064)
			(layers "F.Cu" "F.Mask" "F.Paste")
			(net "FM_BMC_CRASHLOG_TRIG_R2_N")
		)
		(pad "R7" smd circle
			(at -1.199896 5.199888 180)
			(size 0.4064 0.4064)
			(layers "F.Cu" "F.Mask" "F.Paste")
			(net "GPU_NVS_PWR_BRAKE_R_N")
		)
		(pad "R8" smd circle
			(at -0.40005 5.199888 180)
			(size 0.4064 0.4064)
			(layers "F.Cu" "F.Mask" "F.Paste")
			(net "NC_FM_PFR_UPDATE_N")
		)
		(pad "R9" smd circle
			(at 0.40005 5.199888 180)
			(size 0.4064 0.4064)
			(layers "F.Cu" "F.Mask" "F.Paste")
			(net "Net_248")
		)
		(pad "R10" smd circle
			(at 1.199896 5.199888 180)
			(size 0.4064 0.4064)
			(layers "F.Cu" "F.Mask" "F.Paste")
			(net "Net_251")
		)
		(pad "R11" smd circle
			(at 1.999996 5.199888 180)
			(size 0.4064 0.4064)
			(layers "F.Cu" "F.Mask" "F.Paste")
			(net "Net_257")
		)
		(pad "R12" smd circle
			(at 2.800096 5.199888 180)
			(size 0.4064 0.4064)
			(layers "F.Cu" "F.Mask" "F.Paste")
			(net "PU_PB25A")
		)
		(pad "R13" smd circle
			(at 3.599942 5.199888 180)
			(size 0.4064 0.4064)
			(layers "F.Cu" "F.Mask" "F.Paste")
			(net "Net_259")
		)
		(pad "R14" smd circle
			(at 4.400042 5.199888 180)
			(size 0.4064 0.4064)
			(layers "F.Cu" "F.Mask" "F.Paste")
			(net "SMB_BMC_MM16_R4_SDA")
		)
		(pad "R15" smd circle
			(at 5.199888 5.199888 180)
			(size 0.4064 0.4064)
			(layers "F.Cu" "F.Mask" "F.Paste")
			(net "GND")
		)
		(pad "R16" smd circle
			(at 5.999988 5.199888 180)
			(size 0.4064 0.4064)
			(layers "F.Cu" "F.Mask" "F.Paste")
			(net "SMB_BMC_ALERT16_R2_N")
		)
		(pad "T1" smd circle
			(at -5.999988 5.999988 180)
			(size 0.4064 0.4064)
			(layers "F.Cu" "F.Mask" "F.Paste")
			(net "PVCCA_AUX_PLD")
		)
		(pad "T2" smd circle
			(at -5.199888 5.999988 180)
			(size 0.4064 0.4064)
			(layers "F.Cu" "F.Mask" "F.Paste")
			(net "FM_SOL_UART_CH_SEL_R2")
		)
		(pad "T3" smd circle
			(at -4.400042 5.999988 180)
			(size 0.4064 0.4064)
			(layers "F.Cu" "F.Mask" "F.Paste")
			(net "RST_WDTRST_PLD_R2_N")
		)
		(pad "T4" smd circle
			(at -3.599942 5.999988 180)
			(size 0.4064 0.4064)
			(layers "F.Cu" "F.Mask" "F.Paste")
			(net "Net_45")
		)
		(pad "T5" smd circle
			(at -2.800096 5.999988 180)
			(size 0.4064 0.4064)
			(layers "F.Cu" "F.Mask" "F.Paste")
			(net "IRQ_PCH_TPM_SPI_R2_N")
		)
		(pad "T6" smd circle
			(at -1.999996 5.999988 180)
			(size 0.4064 0.4064)
			(layers "F.Cu" "F.Mask" "F.Paste")
			(net "FM_PCH_BEEP_LED")
		)
		(pad "T7" smd circle
			(at -1.199896 5.999988 180)
			(size 0.4064 0.4064)
			(layers "F.Cu" "F.Mask" "F.Paste")
			(net "RST_PFR_OVR_RTC_R")
		)
		(pad "T8" smd circle
			(at -0.40005 5.999988 180)
			(size 0.4064 0.4064)
			(layers "F.Cu" "F.Mask" "F.Paste")
			(net "FM_JTAG_TCK_MUX_BMC_SEL")
		)
		(pad "T9" smd circle
			(at 0.40005 5.999988 180)
			(size 0.4064 0.4064)
			(layers "F.Cu" "F.Mask" "F.Paste")
			(net "PWRGD_P1V2_AUX_R1")
		)
		(pad "T10" smd circle
			(at 1.199896 5.999988 180)
			(size 0.4064 0.4064)
			(layers "F.Cu" "F.Mask" "F.Paste")
			(net "Net_249")
		)
		(pad "T11" smd circle
			(at 1.999996 5.999988 180)
			(size 0.4064 0.4064)
			(layers "F.Cu" "F.Mask" "F.Paste")
			(net "Net_254")
		)
		(pad "T12" smd circle
			(at 2.800096 5.999988 180)
			(size 0.4064 0.4064)
			(layers "F.Cu" "F.Mask" "F.Paste")
			(net "Net_258")
		)
		(pad "T13" smd circle
			(at 3.599942 5.999988 180)
			(size 0.4064 0.4064)
			(layers "F.Cu" "F.Mask" "F.Paste")
			(net "Net_262")
		)
		(pad "T14" smd circle
			(at 4.400042 5.999988 180)
			(size 0.4064 0.4064)
			(layers "F.Cu" "F.Mask" "F.Paste")
			(net "Net_260")
		)
		(pad "T15" smd circle
			(at 5.199888 5.999988 180)
			(size 0.4064 0.4064)
			(layers "F.Cu" "F.Mask" "F.Paste")
			(net "SMB_BMC_MM16_R4_SCL")
		)
		(pad "T16" smd circle
			(at 5.999988 5.999988 180)
			(size 0.4064 0.4064)
			(layers "F.Cu" "F.Mask" "F.Paste")
			(net "PVCCA_AUX_PLD")
		)
	)
)
